#ISCELL
  pure_quanta quanta_title_block_c *
  *
#ISCELL
  logical_power vcc_core *
  page37_i10
#ISCELL
  logical_power vcc_core *
  page37_i11
#ISCELL
  logical_power vcc_core *
  page37_i12
#ISCELL
  logical_power vcc_core *
  page37_i13
#ISCELL
  logical_power universal_gnd *
  page37_i14
#CELL
  pure_quanta q_cap *
  page37_i15
#ISCELL
  logical_power vcc_core *
  page37_i2
#ISCELL
  logical_power vcc_core *
  page37_i4
#ISCELL
  logical_power vcc_core *
  page37_i5
#ISCELL
  logical_power vcc_core *
  page37_i6
#CELL
  pure_quanta socket4677_azif0045p001c01cs *
  page37_i7
#CELL
  pure_quanta socket4677_azif0045p001c01cs *
  page37_i8
#ISCELL
  logical_power vcc_core *
  page37_i9
